FILE_TYPE = MACRO_DRAWING;
SET COLOR_WIRE YELLOW;
SET COLOR_PROP ORANGE;
SET COLOR_DOT WHITE;
SET COLOR_ARC YELLOW;
SET COLOR_BODY GREEN;
SET COLOR_NOTE PURPLE;
SET PROP_DISPLAY VALUE;
SET PAGE_NUMBER P126;
FORCEADD Q_RES..1
(-1700 -150);
FORCEPROP 1 LAST PART_NUMBER CS12402FB01
J 0
(-1800 -100);
DISPLAY 0.510638 (-1800 -100);
DISPLAY INVISIBLE (-1800 -100);
FORCEPROP 1 LAST WATTAGE 1/16W
J 2
(-1525 -75);
DISPLAY 0.510638 (-1525 -75);
FORCEPROP 1 LAST PACK_TYPE 0402LF
J 0
(-1800 -75);
DISPLAY 0.510638 (-1800 -75);
FORCEPROP 1 LAST VALUE 240
J 2
(-1500 -150);
DISPLAY 0.638298 (-1500 -150);
FORCEPROP 1 LAST MATERIAL EMPTY
J 0
(-1375 -150);
DISPLAY 0.638298 (-1375 -150);
PAINT RED (-1375 -150);
FORCEPROP 1 LAST TOLERANCE 1%
J 0
(-1475 -150);
DISPLAY 0.638298 (-1475 -150);
FORCEPROP 1 LAST $LOCATION R97
J 0
(-1925 -150);
DISPLAY 0.787234 (-1925 -150);
FORCEPROP 1 LASTPIN (-1800 -150) $PN 1
J 0
(-1788 -138);
DISPLAY 0.787234 (-1788 -138);
FORCEPROP 1 LASTPIN (-1600 -150) $PN 2
J 0
(-1638 -138);
DISPLAY 0.787234 (-1638 -138);
FORCEPROP 2 LAST CDS_LIB pure_quanta
J 0
(-1700 -150);
PAINT MONO (-1700 -150);
DISPLAY INVISIBLE (-1700 -150);
FORCEPROP 1 LAST PATH I114
J 0
(-1750 0);
DISPLAY 0.978723 (-1750 0);
PAINT WHITE (-1750 0);
DISPLAY INVISIBLE (-1750 0);
FORCEPROP 2 LAST CDS_LOCATION R97
J 0
(-1750 50);
DISPLAY 1.021277 (-1750 50);
DISPLAY INVISIBLE (-1750 50);
FORCEPROP 2 LAST $SEC 1
J 0
(-1750 50);
DISPLAY 0.680851 (-1750 50);
PAINT MONO (-1750 50);
DISPLAY INVISIBLE (-1750 50);
FORCEPROP 2 LAST CDS_SEC 1
J 0
(-1750 50);
DISPLAY 1.021277 (-1750 50);
DISPLAY INVISIBLE (-1750 50);
FORCEADD OFFPAGE..2
(-300 -1100);
FORCEPROP 2 LAST $XR0 50 
J 0
(-111 -1100);
DISPLAY 0.638298 (-111 -1100);
PAINT MONO (-111 -1100);
FORCEPROP 2 LAST CDS_LIB standard
J 0
(-300 -1100);
DISPLAY INVISIBLE (-300 -1100);
FORCEPROP 1 LAST OFFPAGE TRUE
J 0
(25 -1225);
DISPLAY 0.872340 (25 -1225);
PAINT GREEN (25 -1225);
DISPLAY INVISIBLE (25 -1225);
FORCEPROP 1 LAST COMMENT_BODY TRUE
J 0
(-345 -1195);
DISPLAY 0.872340 (-345 -1195);
PAINT GREEN (-345 -1195);
DISPLAY INVISIBLE (-345 -1195);
FORCEPROP 2 LAST PATH I133
J 0
(-100 -1050);
DISPLAY 1.021277 (-100 -1050);
DISPLAY INVISIBLE (-100 -1050);
FORCEADD OFFPAGE..2
(-300 -1225);
FORCEPROP 2 LAST $XR0 50 
J 0
(-111 -1225);
DISPLAY 0.638298 (-111 -1225);
PAINT MONO (-111 -1225);
FORCEPROP 2 LAST CDS_LIB standard
J 0
(-300 -1225);
DISPLAY INVISIBLE (-300 -1225);
FORCEPROP 1 LAST OFFPAGE TRUE
J 0
(25 -1350);
DISPLAY 0.872340 (25 -1350);
PAINT GREEN (25 -1350);
DISPLAY INVISIBLE (25 -1350);
FORCEPROP 1 LAST COMMENT_BODY TRUE
J 0
(-345 -1320);
DISPLAY 0.872340 (-345 -1320);
PAINT GREEN (-345 -1320);
DISPLAY INVISIBLE (-345 -1320);
FORCEPROP 2 LAST PATH I134
J 0
(-100 -1175);
DISPLAY 1.021277 (-100 -1175);
DISPLAY INVISIBLE (-100 -1175);
FORCEADD Q_RES..1
(-1725 -1100);
FORCEPROP 1 LAST PART_NUMBER CS12402FB01
J 0
(-1825 -1050);
DISPLAY 0.510638 (-1825 -1050);
DISPLAY INVISIBLE (-1825 -1050);
FORCEPROP 1 LAST TOLERANCE 1%
J 0
(-1500 -1100);
DISPLAY 0.638298 (-1500 -1100);
FORCEPROP 1 LAST MATERIAL EMPTY
J 0
(-1400 -1100);
DISPLAY 0.638298 (-1400 -1100);
PAINT RED (-1400 -1100);
FORCEPROP 1 LAST VALUE 240
J 2
(-1525 -1100);
DISPLAY 0.638298 (-1525 -1100);
FORCEPROP 1 LAST WATTAGE 1/16W
J 2
(-1550 -1025);
DISPLAY 0.510638 (-1550 -1025);
FORCEPROP 1 LAST PACK_TYPE 0402LF
J 0
(-1825 -1025);
DISPLAY 0.510638 (-1825 -1025);
FORCEPROP 1 LAST $LOCATION R90
J 0
(-1950 -1100);
DISPLAY 0.787234 (-1950 -1100);
FORCEPROP 1 LASTPIN (-1825 -1100) $PN 1
J 0
(-1813 -1088);
DISPLAY 0.787234 (-1813 -1088);
FORCEPROP 1 LASTPIN (-1625 -1100) $PN 2
J 0
(-1663 -1088);
DISPLAY 0.787234 (-1663 -1088);
FORCEPROP 2 LAST CDS_LIB pure_quanta
J 0
(-1725 -1100);
PAINT MONO (-1725 -1100);
DISPLAY INVISIBLE (-1725 -1100);
FORCEPROP 1 LAST PATH I135
J 0
(-1775 -950);
DISPLAY 0.978723 (-1775 -950);
PAINT WHITE (-1775 -950);
DISPLAY INVISIBLE (-1775 -950);
FORCEPROP 2 LAST CDS_LOCATION R90
J 0
(-1775 -900);
DISPLAY 1.021277 (-1775 -900);
DISPLAY INVISIBLE (-1775 -900);
FORCEPROP 2 LAST $SEC 1
J 0
(-1775 -900);
DISPLAY 0.680851 (-1775 -900);
PAINT MONO (-1775 -900);
DISPLAY INVISIBLE (-1775 -900);
FORCEPROP 2 LAST CDS_SEC 1
J 0
(-1775 -900);
DISPLAY 1.021277 (-1775 -900);
DISPLAY INVISIBLE (-1775 -900);
FORCEADD Q_RES..1
(-1725 -1225);
FORCEPROP 1 LAST PART_NUMBER CS12402FB01
J 0
(-1825 -1175);
DISPLAY 0.510638 (-1825 -1175);
DISPLAY INVISIBLE (-1825 -1175);
FORCEPROP 1 LAST PACK_TYPE 0402LF
J 0
(-1825 -1150);
DISPLAY 0.510638 (-1825 -1150);
FORCEPROP 1 LAST WATTAGE 1/16W
J 2
(-1550 -1150);
DISPLAY 0.510638 (-1550 -1150);
FORCEPROP 1 LAST VALUE 240
J 2
(-1525 -1225);
DISPLAY 0.638298 (-1525 -1225);
FORCEPROP 1 LAST TOLERANCE 1%
J 0
(-1500 -1225);
DISPLAY 0.638298 (-1500 -1225);
FORCEPROP 1 LAST MATERIAL EMPTY
J 0
(-1400 -1225);
DISPLAY 0.638298 (-1400 -1225);
PAINT RED (-1400 -1225);
FORCEPROP 1 LAST $LOCATION R91
J 0
(-1950 -1225);
DISPLAY 0.787234 (-1950 -1225);
FORCEPROP 1 LASTPIN (-1825 -1225) $PN 1
J 0
(-1813 -1213);
DISPLAY 0.787234 (-1813 -1213);
FORCEPROP 1 LASTPIN (-1625 -1225) $PN 2
J 0
(-1663 -1213);
DISPLAY 0.787234 (-1663 -1213);
FORCEPROP 2 LAST CDS_LIB pure_quanta
J 0
(-1725 -1225);
PAINT MONO (-1725 -1225);
DISPLAY INVISIBLE (-1725 -1225);
FORCEPROP 1 LAST PATH I136
J 0
(-1775 -1075);
DISPLAY 0.978723 (-1775 -1075);
PAINT WHITE (-1775 -1075);
DISPLAY INVISIBLE (-1775 -1075);
FORCEPROP 2 LAST CDS_LOCATION R91
J 0
(-1775 -1025);
DISPLAY 1.021277 (-1775 -1025);
DISPLAY INVISIBLE (-1775 -1025);
FORCEPROP 2 LAST $SEC 1
J 0
(-1775 -1025);
DISPLAY 0.680851 (-1775 -1025);
PAINT MONO (-1775 -1025);
DISPLAY INVISIBLE (-1775 -1025);
FORCEPROP 2 LAST CDS_SEC 1
J 0
(-1775 -1025);
DISPLAY 1.021277 (-1775 -1025);
DISPLAY INVISIBLE (-1775 -1025);
FORCEADD UNIVERSAL_POWER..1
(-2075 -850);
FORCEPROP 3 LASTPIN (-2075 -900) SIG_NAME PVNN_TERM_CPU1\g
J 0
(-2065 -890);
DISPLAY 0.659574 (-2065 -890);
PAINT MONO (-2065 -890);
DISPLAY INVISIBLE (-2065 -890);
FORCEPROP 1 LAST HDL_POWER PVNN_TERM_CPU1
J 1
(-2075 -800);
DISPLAY 0.872340 (-2075 -800);
PAINT GREEN (-2075 -800);
FORCEPROP 2 LAST CDS_LIB logical_power
J 0
(-2075 -850);
DISPLAY INVISIBLE (-2075 -850);
FORCEPROP 1 LAST PATH I137
J 0
(-2025 -825);
DISPLAY 0.872340 (-2025 -825);
PAINT AQUA (-2025 -825);
DISPLAY INVISIBLE (-2025 -825);
FORCEADD OFFPAGE..2
(-300 -1350);
FORCEPROP 2 LAST $XR0 50 
J 0
(-111 -1350);
DISPLAY 0.638298 (-111 -1350);
PAINT MONO (-111 -1350);
FORCEPROP 2 LAST CDS_LIB standard
J 0
(-300 -1350);
DISPLAY INVISIBLE (-300 -1350);
FORCEPROP 1 LAST OFFPAGE TRUE
J 0
(25 -1475);
DISPLAY 0.872340 (25 -1475);
PAINT GREEN (25 -1475);
DISPLAY INVISIBLE (25 -1475);
FORCEPROP 1 LAST COMMENT_BODY TRUE
J 0
(-345 -1445);
DISPLAY 0.872340 (-345 -1445);
PAINT GREEN (-345 -1445);
DISPLAY INVISIBLE (-345 -1445);
FORCEPROP 2 LAST PATH I138
J 0
(-100 -1300);
DISPLAY 1.021277 (-100 -1300);
DISPLAY INVISIBLE (-100 -1300);
FORCEADD OFFPAGE..2
(-300 -1475);
FORCEPROP 2 LAST $XR0 50 
J 0
(-111 -1475);
DISPLAY 0.638298 (-111 -1475);
PAINT MONO (-111 -1475);
FORCEPROP 2 LAST CDS_LIB standard
J 0
(-300 -1475);
DISPLAY INVISIBLE (-300 -1475);
FORCEPROP 1 LAST OFFPAGE TRUE
J 0
(25 -1600);
DISPLAY 0.872340 (25 -1600);
PAINT GREEN (25 -1600);
DISPLAY INVISIBLE (25 -1600);
FORCEPROP 1 LAST COMMENT_BODY TRUE
J 0
(-345 -1570);
DISPLAY 0.872340 (-345 -1570);
PAINT GREEN (-345 -1570);
DISPLAY INVISIBLE (-345 -1570);
FORCEPROP 2 LAST PATH I139
J 0
(-100 -1425);
DISPLAY 1.021277 (-100 -1425);
DISPLAY INVISIBLE (-100 -1425);
FORCEADD Q_RES..1
(-1725 -1350);
FORCEPROP 1 LAST PART_NUMBER CS12402FB01
J 0
(-1825 -1300);
DISPLAY 0.510638 (-1825 -1300);
DISPLAY INVISIBLE (-1825 -1300);
FORCEPROP 1 LAST PACK_TYPE 0402LF
J 0
(-1825 -1275);
DISPLAY 0.510638 (-1825 -1275);
FORCEPROP 1 LAST WATTAGE 1/16W
J 2
(-1550 -1275);
DISPLAY 0.510638 (-1550 -1275);
FORCEPROP 1 LAST VALUE 240
J 2
(-1525 -1350);
DISPLAY 0.638298 (-1525 -1350);
FORCEPROP 1 LAST TOLERANCE 1%
J 0
(-1500 -1350);
DISPLAY 0.638298 (-1500 -1350);
FORCEPROP 1 LAST MATERIAL EMPTY
J 0
(-1400 -1350);
DISPLAY 0.638298 (-1400 -1350);
PAINT RED (-1400 -1350);
FORCEPROP 1 LAST $LOCATION R92
J 0
(-1950 -1350);
DISPLAY 0.787234 (-1950 -1350);
FORCEPROP 1 LASTPIN (-1825 -1350) $PN 1
J 0
(-1813 -1338);
DISPLAY 0.787234 (-1813 -1338);
FORCEPROP 1 LASTPIN (-1625 -1350) $PN 2
J 0
(-1663 -1338);
DISPLAY 0.787234 (-1663 -1338);
FORCEPROP 2 LAST CDS_LIB pure_quanta
J 0
(-1725 -1350);
PAINT MONO (-1725 -1350);
DISPLAY INVISIBLE (-1725 -1350);
FORCEPROP 1 LAST PATH I140
J 0
(-1775 -1200);
DISPLAY 0.978723 (-1775 -1200);
PAINT WHITE (-1775 -1200);
DISPLAY INVISIBLE (-1775 -1200);
FORCEPROP 2 LAST CDS_LOCATION R92
J 0
(-1775 -1150);
DISPLAY 1.021277 (-1775 -1150);
DISPLAY INVISIBLE (-1775 -1150);
FORCEPROP 2 LAST $SEC 1
J 0
(-1775 -1150);
DISPLAY 0.680851 (-1775 -1150);
PAINT MONO (-1775 -1150);
DISPLAY INVISIBLE (-1775 -1150);
FORCEPROP 2 LAST CDS_SEC 1
J 0
(-1775 -1150);
DISPLAY 1.021277 (-1775 -1150);
DISPLAY INVISIBLE (-1775 -1150);
FORCEADD Q_RES..1
(-1725 -1475);
FORCEPROP 1 LAST PART_NUMBER CS12402FB01
J 0
(-1825 -1425);
DISPLAY 0.510638 (-1825 -1425);
DISPLAY INVISIBLE (-1825 -1425);
FORCEPROP 1 LAST PACK_TYPE 0402LF
J 0
(-1825 -1400);
DISPLAY 0.510638 (-1825 -1400);
FORCEPROP 1 LAST WATTAGE 1/16W
J 2
(-1550 -1400);
DISPLAY 0.510638 (-1550 -1400);
FORCEPROP 1 LAST VALUE 240
J 2
(-1525 -1475);
DISPLAY 0.638298 (-1525 -1475);
FORCEPROP 1 LAST MATERIAL EMPTY
J 0
(-1400 -1475);
DISPLAY 0.638298 (-1400 -1475);
PAINT RED (-1400 -1475);
FORCEPROP 1 LAST TOLERANCE 1%
J 0
(-1500 -1475);
DISPLAY 0.638298 (-1500 -1475);
FORCEPROP 1 LAST $LOCATION R93
J 0
(-1950 -1475);
DISPLAY 0.787234 (-1950 -1475);
FORCEPROP 1 LASTPIN (-1825 -1475) $PN 1
J 0
(-1813 -1463);
DISPLAY 0.787234 (-1813 -1463);
FORCEPROP 1 LASTPIN (-1625 -1475) $PN 2
J 0
(-1663 -1463);
DISPLAY 0.787234 (-1663 -1463);
FORCEPROP 2 LAST CDS_LIB pure_quanta
J 0
(-1725 -1475);
PAINT MONO (-1725 -1475);
DISPLAY INVISIBLE (-1725 -1475);
FORCEPROP 1 LAST PATH I141
J 0
(-1775 -1325);
DISPLAY 0.978723 (-1775 -1325);
PAINT WHITE (-1775 -1325);
DISPLAY INVISIBLE (-1775 -1325);
FORCEPROP 2 LAST CDS_LOCATION R93
J 0
(-1775 -1275);
DISPLAY 1.021277 (-1775 -1275);
DISPLAY INVISIBLE (-1775 -1275);
FORCEPROP 2 LAST $SEC 1
J 0
(-1775 -1275);
DISPLAY 0.680851 (-1775 -1275);
PAINT MONO (-1775 -1275);
DISPLAY INVISIBLE (-1775 -1275);
FORCEPROP 2 LAST CDS_SEC 1
J 0
(-1775 -1275);
DISPLAY 1.021277 (-1775 -1275);
DISPLAY INVISIBLE (-1775 -1275);
FORCEADD Q_RES..1
(-1700 -25);
FORCEPROP 1 LAST PART_NUMBER CS12402FB01
J 0
(-1800 25);
DISPLAY 0.510638 (-1800 25);
DISPLAY INVISIBLE (-1800 25);
FORCEPROP 1 LAST VALUE 240
J 2
(-1500 -25);
DISPLAY 0.638298 (-1500 -25);
FORCEPROP 1 LAST TOLERANCE 1%
J 0
(-1475 -25);
DISPLAY 0.638298 (-1475 -25);
FORCEPROP 1 LAST PACK_TYPE 0402LF
J 0
(-1800 50);
DISPLAY 0.510638 (-1800 50);
FORCEPROP 1 LAST WATTAGE 1/16W
J 2
(-1525 50);
DISPLAY 0.510638 (-1525 50);
FORCEPROP 1 LAST MATERIAL EMPTY
J 0
(-1375 -25);
DISPLAY 0.638298 (-1375 -25);
PAINT RED (-1375 -25);
FORCEPROP 1 LAST $LOCATION R96
J 0
(-1925 -25);
DISPLAY 0.787234 (-1925 -25);
FORCEPROP 1 LASTPIN (-1800 -25) $PN 1
J 0
(-1788 -13);
DISPLAY 0.787234 (-1788 -13);
FORCEPROP 1 LASTPIN (-1600 -25) $PN 2
J 0
(-1638 -13);
DISPLAY 0.787234 (-1638 -13);
FORCEPROP 2 LAST CDS_LIB pure_quanta
J 0
(-1700 -25);
PAINT MONO (-1700 -25);
DISPLAY INVISIBLE (-1700 -25);
FORCEPROP 1 LAST PATH I22
J 0
(-1750 125);
DISPLAY 0.978723 (-1750 125);
PAINT WHITE (-1750 125);
DISPLAY INVISIBLE (-1750 125);
FORCEPROP 2 LAST CDS_LOCATION R96
J 0
(-1750 175);
DISPLAY 1.021277 (-1750 175);
DISPLAY INVISIBLE (-1750 175);
FORCEPROP 2 LAST $SEC 1
J 0
(-1750 175);
DISPLAY 0.680851 (-1750 175);
PAINT MONO (-1750 175);
DISPLAY INVISIBLE (-1750 175);
FORCEPROP 2 LAST CDS_SEC 1
J 0
(-1750 175);
DISPLAY 1.021277 (-1750 175);
DISPLAY INVISIBLE (-1750 175);
FORCEADD Q_RES..1
(-1700 100);
FORCEPROP 1 LAST PART_NUMBER CS12402FB01
J 0
(-1800 150);
DISPLAY 0.510638 (-1800 150);
DISPLAY INVISIBLE (-1800 150);
FORCEPROP 1 LAST MATERIAL EMPTY
J 0
(-1375 100);
DISPLAY 0.638298 (-1375 100);
PAINT RED (-1375 100);
FORCEPROP 1 LAST PACK_TYPE 0402LF
J 0
(-1800 175);
DISPLAY 0.510638 (-1800 175);
FORCEPROP 1 LAST TOLERANCE 1%
J 0
(-1475 100);
DISPLAY 0.638298 (-1475 100);
FORCEPROP 1 LAST VALUE 240
J 2
(-1500 100);
DISPLAY 0.638298 (-1500 100);
FORCEPROP 1 LAST WATTAGE 1/16W
J 2
(-1525 175);
DISPLAY 0.510638 (-1525 175);
FORCEPROP 1 LAST $LOCATION R95
J 0
(-1925 100);
DISPLAY 0.787234 (-1925 100);
FORCEPROP 1 LASTPIN (-1800 100) $PN 1
J 0
(-1788 112);
DISPLAY 0.787234 (-1788 112);
FORCEPROP 1 LASTPIN (-1600 100) $PN 2
J 0
(-1638 112);
DISPLAY 0.787234 (-1638 112);
FORCEPROP 2 LAST CDS_LIB pure_quanta
J 0
(-1700 100);
PAINT MONO (-1700 100);
DISPLAY INVISIBLE (-1700 100);
FORCEPROP 1 LAST PATH I23
J 0
(-1750 250);
DISPLAY 0.978723 (-1750 250);
PAINT WHITE (-1750 250);
DISPLAY INVISIBLE (-1750 250);
FORCEPROP 2 LAST CDS_LOCATION R95
J 0
(-1750 300);
DISPLAY 1.021277 (-1750 300);
DISPLAY INVISIBLE (-1750 300);
FORCEPROP 2 LAST $SEC 1
J 0
(-1750 300);
DISPLAY 0.680851 (-1750 300);
PAINT MONO (-1750 300);
DISPLAY INVISIBLE (-1750 300);
FORCEPROP 2 LAST CDS_SEC 1
J 0
(-1750 300);
DISPLAY 1.021277 (-1750 300);
DISPLAY INVISIBLE (-1750 300);
FORCEADD UNIVERSAL_POWER..1
(-2050 475);
FORCEPROP 3 LASTPIN (-2050 425) SIG_NAME PVNN_TERM_CPU0\g
J 0
(-2040 435);
DISPLAY 0.659574 (-2040 435);
PAINT MONO (-2040 435);
DISPLAY INVISIBLE (-2040 435);
FORCEPROP 1 LAST HDL_POWER PVNN_TERM_CPU0
J 1
(-2050 525);
DISPLAY 0.872340 (-2050 525);
PAINT GREEN (-2050 525);
FORCEPROP 2 LAST CDS_LIB logical_power
J 0
(-2050 475);
DISPLAY INVISIBLE (-2050 475);
FORCEPROP 1 LAST PATH I24
J 0
(-2000 500);
DISPLAY 0.872340 (-2000 500);
PAINT AQUA (-2000 500);
DISPLAY INVISIBLE (-2000 500);
FORCEADD Q_RES..1
(-1700 225);
FORCEPROP 1 LAST PART_NUMBER CS12402FB01
J 0
(-1800 275);
DISPLAY 0.510638 (-1800 275);
DISPLAY INVISIBLE (-1800 275);
FORCEPROP 1 LAST MATERIAL EMPTY
J 0
(-1375 225);
DISPLAY 0.638298 (-1375 225);
PAINT RED (-1375 225);
FORCEPROP 1 LAST PACK_TYPE 0402LF
J 0
(-1800 300);
DISPLAY 0.510638 (-1800 300);
FORCEPROP 1 LAST TOLERANCE 1%
J 0
(-1475 225);
DISPLAY 0.638298 (-1475 225);
FORCEPROP 1 LAST VALUE 240
J 2
(-1500 225);
DISPLAY 0.638298 (-1500 225);
FORCEPROP 1 LAST WATTAGE 1/16W
J 2
(-1525 300);
DISPLAY 0.510638 (-1525 300);
FORCEPROP 1 LAST $LOCATION R94
J 0
(-1925 225);
DISPLAY 0.787234 (-1925 225);
FORCEPROP 1 LASTPIN (-1800 225) $PN 1
J 0
(-1788 237);
DISPLAY 0.787234 (-1788 237);
FORCEPROP 1 LASTPIN (-1600 225) $PN 2
J 0
(-1638 237);
DISPLAY 0.787234 (-1638 237);
FORCEPROP 2 LAST CDS_LIB pure_quanta
J 0
(-1700 225);
PAINT MONO (-1700 225);
DISPLAY INVISIBLE (-1700 225);
FORCEPROP 1 LAST PATH I25
J 0
(-1750 375);
DISPLAY 0.978723 (-1750 375);
PAINT WHITE (-1750 375);
DISPLAY INVISIBLE (-1750 375);
FORCEPROP 2 LAST CDS_LOCATION R94
J 0
(-1750 425);
DISPLAY 1.021277 (-1750 425);
DISPLAY INVISIBLE (-1750 425);
FORCEPROP 2 LAST $SEC 1
J 0
(-1750 425);
DISPLAY 0.680851 (-1750 425);
PAINT MONO (-1750 425);
DISPLAY INVISIBLE (-1750 425);
FORCEPROP 2 LAST CDS_SEC 1
J 0
(-1750 425);
DISPLAY 1.021277 (-1750 425);
DISPLAY INVISIBLE (-1750 425);
FORCEADD OFFPAGE..2
(-275 -150);
FORCEPROP 2 LAST $XR0 19 
J 0
(-86 -150);
DISPLAY 0.638298 (-86 -150);
PAINT MONO (-86 -150);
FORCEPROP 2 LAST CDS_LIB standard
J 0
(-275 -150);
DISPLAY INVISIBLE (-275 -150);
FORCEPROP 1 LAST OFFPAGE TRUE
J 0
(50 -275);
DISPLAY 0.872340 (50 -275);
PAINT GREEN (50 -275);
DISPLAY INVISIBLE (50 -275);
FORCEPROP 1 LAST COMMENT_BODY TRUE
J 0
(-320 -245);
DISPLAY 0.872340 (-320 -245);
PAINT GREEN (-320 -245);
DISPLAY INVISIBLE (-320 -245);
FORCEPROP 2 LAST PATH I42
J 0
(-75 -100);
DISPLAY 1.021277 (-75 -100);
DISPLAY INVISIBLE (-75 -100);
FORCEADD OFFPAGE..2
(-275 -25);
FORCEPROP 2 LAST $XR0 19 
J 0
(-86 -25);
DISPLAY 0.638298 (-86 -25);
PAINT MONO (-86 -25);
FORCEPROP 2 LAST CDS_LIB standard
J 0
(-275 -25);
DISPLAY INVISIBLE (-275 -25);
FORCEPROP 1 LAST OFFPAGE TRUE
J 0
(50 -150);
DISPLAY 0.872340 (50 -150);
PAINT GREEN (50 -150);
DISPLAY INVISIBLE (50 -150);
FORCEPROP 1 LAST COMMENT_BODY TRUE
J 0
(-320 -120);
DISPLAY 0.872340 (-320 -120);
PAINT GREEN (-320 -120);
DISPLAY INVISIBLE (-320 -120);
FORCEPROP 2 LAST PATH I43
J 0
(-75 25);
DISPLAY 1.021277 (-75 25);
DISPLAY INVISIBLE (-75 25);
FORCEADD OFFPAGE..2
(-275 100);
FORCEPROP 2 LAST $XR0 19 
J 0
(-86 100);
DISPLAY 0.638298 (-86 100);
PAINT MONO (-86 100);
FORCEPROP 2 LAST CDS_LIB standard
J 0
(-275 100);
DISPLAY INVISIBLE (-275 100);
FORCEPROP 1 LAST OFFPAGE TRUE
J 0
(50 -25);
DISPLAY 0.872340 (50 -25);
PAINT GREEN (50 -25);
DISPLAY INVISIBLE (50 -25);
FORCEPROP 1 LAST COMMENT_BODY TRUE
J 0
(-320 5);
DISPLAY 0.872340 (-320 5);
PAINT GREEN (-320 5);
DISPLAY INVISIBLE (-320 5);
FORCEPROP 2 LAST PATH I44
J 0
(-75 150);
DISPLAY 1.021277 (-75 150);
DISPLAY INVISIBLE (-75 150);
FORCEADD OFFPAGE..2
(-275 225);
FORCEPROP 2 LAST $XR0 19 
J 0
(-86 225);
DISPLAY 0.638298 (-86 225);
PAINT MONO (-86 225);
FORCEPROP 2 LAST CDS_LIB standard
J 0
(-275 225);
DISPLAY INVISIBLE (-275 225);
FORCEPROP 1 LAST OFFPAGE TRUE
J 0
(50 100);
DISPLAY 0.872340 (50 100);
PAINT GREEN (50 100);
DISPLAY INVISIBLE (50 100);
FORCEPROP 1 LAST COMMENT_BODY TRUE
J 0
(-320 130);
DISPLAY 0.872340 (-320 130);
PAINT GREEN (-320 130);
DISPLAY INVISIBLE (-320 130);
FORCEPROP 2 LAST PATH I45
J 0
(-75 275);
DISPLAY 1.021277 (-75 275);
DISPLAY INVISIBLE (-75 275);
FORCEADD QUANTA_TITLE_BLOCK_C..1
(5975 -2275);
FORCEPROP 0 LAST CDS_CON_LAST_MODIFIED Fri Aug 25 14:01:46 2023
J 0
(4090 -2260);
PAINT MONO (4090 -2260);
DISPLAY INVISIBLE (4090 -2260);
FORCEPROP 2 LAST CUSTOM_TXT_CDS <XR_PAGE_TITLE>
J 0
(-1915 2975);
DISPLAY 0.638298 (-1915 2975);
PAINT PINK (-1915 2975);
DISPLAY INVISIBLE (-1915 2975);
FORCEPROP 2 LAST CUSTOM_TXT_CDS <NAME_2>
J 0
(2800 -2225);
FORCEPROP 2 LAST CUSTOM_TXT_CDS <NAME_1>
J 0
(2800 -2100);
FORCEPROP 2 LAST CUSTOM_TXT_CDS <Q_NUMBER>
J 0
(4572 -2172);
DISPLAY 1.212766 (4572 -2172);
FORCEPROP 2 LAST CUSTOM_TXT_CDS <Q_PROJ>
J 0
(3593 -2173);
DISPLAY 1.212766 (3593 -2173);
FORCEPROP 2 LAST CUSTOM_TXT_CDS <Q_REV>
J 0
(5791 -2172);
DISPLAY 1.212766 (5791 -2172);
FORCEPROP 2 LAST CUSTOM_TXT_CDS <CON_PAGE_NUM> OF <CON_TOTAL_PAGES>
J 0
(5529 -2257);
DISPLAY 0.978723 (5529 -2257);
FORCEPROP 2 LAST CUSTOM_TXT_CDS <CON_LAST_MODIFIED>
J 0
(4090 -2260);
DISPLAY 0.978723 (4090 -2260);
FORCEPROP 1 LAST Q_TITLE SPR CPU0 & 1- MONF/FIST
J 0
(-3291 -2274);
DISPLAY 2.446809 (-3291 -2274);
PAINT GREEN (-3291 -2274);
FORCEPROP 1 LAST Q_DEPT 
J 1
(2212 -2226);
DISPLAY 1.957447 (2212 -2226);
PAINT GREEN (2212 -2226);
FORCEPROP 2 LAST CDS_XR_PAGE_TITLE CR-126 : @S9S_MB_2U_LIB.S9S_MB_2U(SCH_1):PAGE126
J 0
(-1915 2975);
DISPLAY 0.638298 (-1915 2975);
PAINT PINK (-1915 2975);
DISPLAY INVISIBLE (-1915 2975);
FORCEPROP 2 LAST CDS_LIB pure_quanta
J 0
(5975 -2275);
PAINT MONO (5975 -2275);
DISPLAY INVISIBLE (5975 -2275);
FORCEPROP 1 LAST CDS_LMAN_SYM_OUTLINE -9475,6775,100,-125
J 0
(5975 -2275);
DISPLAY 0.468085 (5975 -2275);
PAINT GREEN (5975 -2275);
DISPLAY INVISIBLE (5975 -2275);
FORCEPROP 1 LAST COMMENT_BODY TRUE
J 0
(5987 -2288);
DISPLAY 0.978723 (5987 -2288);
PAINT GREEN (5987 -2288);
DISPLAY INVISIBLE (5987 -2288);
FORCEPROP 2 LAST PAGE_BORDER TRUE
J 0
(-1915 2975);
DISPLAY 0.638298 (-1915 2975);
PAINT PINK (-1915 2975);
DISPLAY INVISIBLE (-1915 2975);
FORCEADD DNS..1
(-1675 -150);
PAINT RED (-1675 -150);
FORCEPROP 2 LAST CDS_LIB mstr_misc
J 0
(-1675 -150);
PAINT MONO (-1675 -150);
DISPLAY INVISIBLE (-1675 -150);
FORCEPROP 1 LAST COMMENT_BODY TRUE
R 1
J 0
(-1600 -375);
DISPLAY 0.872340 (-1600 -375);
PAINT GREEN (-1600 -375);
DISPLAY INVISIBLE (-1600 -375);
FORCEADD DNS..1
(-1700 -1475);
PAINT RED (-1700 -1475);
FORCEPROP 2 LAST CDS_LIB mstr_misc
J 0
(-1700 -1475);
PAINT MONO (-1700 -1475);
DISPLAY INVISIBLE (-1700 -1475);
FORCEPROP 1 LAST COMMENT_BODY TRUE
R 1
J 0
(-1625 -1700);
DISPLAY 0.872340 (-1625 -1700);
PAINT GREEN (-1625 -1700);
DISPLAY INVISIBLE (-1625 -1700);
FORCEADD DNS..1
(-1675 225);
PAINT RED (-1675 225);
FORCEPROP 2 LAST CDS_LIB mstr_misc
J 0
(-1675 225);
DISPLAY INVISIBLE (-1675 225);
FORCEPROP 1 LAST COMMENT_BODY TRUE
R 1
J 0
(-1600 0);
DISPLAY 0.872340 (-1600 0);
PAINT GREEN (-1600 0);
DISPLAY INVISIBLE (-1600 0);
FORCEADD DNS..1
(-1700 -1350);
PAINT RED (-1700 -1350);
FORCEPROP 2 LAST CDS_LIB mstr_misc
J 0
(-1700 -1350);
DISPLAY INVISIBLE (-1700 -1350);
FORCEPROP 1 LAST COMMENT_BODY TRUE
R 1
J 0
(-1625 -1575);
DISPLAY 0.872340 (-1625 -1575);
PAINT GREEN (-1625 -1575);
DISPLAY INVISIBLE (-1625 -1575);
FORCEADD DNS..1
(-1700 -1100);
PAINT RED (-1700 -1100);
FORCEPROP 2 LAST CDS_LIB mstr_misc
J 0
(-1700 -1100);
DISPLAY INVISIBLE (-1700 -1100);
FORCEPROP 1 LAST COMMENT_BODY TRUE
R 1
J 0
(-1625 -1325);
DISPLAY 0.872340 (-1625 -1325);
PAINT GREEN (-1625 -1325);
DISPLAY INVISIBLE (-1625 -1325);
FORCEADD DNS..1
(-1675 -25);
PAINT RED (-1675 -25);
FORCEPROP 2 LAST CDS_LIB mstr_misc
J 0
(-1675 -25);
DISPLAY INVISIBLE (-1675 -25);
FORCEPROP 1 LAST COMMENT_BODY TRUE
R 1
J 0
(-1600 -250);
DISPLAY 0.872340 (-1600 -250);
PAINT GREEN (-1600 -250);
DISPLAY INVISIBLE (-1600 -250);
FORCEADD DNS..1
(-1700 -1225);
PAINT RED (-1700 -1225);
FORCEPROP 2 LAST CDS_LIB mstr_misc
J 0
(-1700 -1225);
DISPLAY INVISIBLE (-1700 -1225);
FORCEPROP 1 LAST COMMENT_BODY TRUE
R 1
J 0
(-1625 -1450);
DISPLAY 0.872340 (-1625 -1450);
PAINT GREEN (-1625 -1450);
DISPLAY INVISIBLE (-1625 -1450);
FORCEADD DNS..1
(-1675 100);
PAINT RED (-1675 100);
FORCEPROP 2 LAST CDS_LIB mstr_misc
J 0
(-1675 100);
DISPLAY INVISIBLE (-1675 100);
FORCEPROP 1 LAST COMMENT_BODY TRUE
R 1
J 0
(-1600 -125);
DISPLAY 0.872340 (-1600 -125);
PAINT GREEN (-1600 -125);
DISPLAY INVISIBLE (-1600 -125);
WIRE 16 -1 (-2050 425)(-2050 225);
WIRE 16 -1 (-2075 -900)(-2075 -1100);
WIRE 16 -1 (-1600 -150)(-325 -150);
FORCEPROP 2 LAST SIG_NAME PU_CPU0_UPI3_AC_COUPLING
J 0
(-1175 -140);
DISPLAY 0.680851 (-1175 -140);
PAINT WHITE (-1175 -140);
WIRE 16 -1 (-1600 225)(-325 225);
FORCEPROP 2 LAST SIG_NAME PU_CPU0_UPI0_AC_COUPLING
J 0
(-1175 235);
DISPLAY 0.680851 (-1175 235);
PAINT WHITE (-1175 235);
WIRE 16 -1 (-1600 100)(-325 100);
FORCEPROP 2 LAST SIG_NAME PU_CPU0_UPI1_AC_COUPLING
J 0
(-1175 110);
DISPLAY 0.680851 (-1175 110);
PAINT WHITE (-1175 110);
WIRE 16 -1 (-2075 -1475)(-1825 -1475);
WIRE 16 -1 (-2075 -1350)(-2075 -1475);
WIRE 16 -1 (-2075 -1350)(-1825 -1350);
WIRE 16 -1 (-2075 -1225)(-2075 -1350);
WIRE 16 -1 (-2075 -1225)(-1825 -1225);
WIRE 16 -1 (-2075 -1100)(-2075 -1225);
WIRE 16 -1 (-2075 -1100)(-1825 -1100);
WIRE 16 -1 (-1625 -1475)(-350 -1475);
FORCEPROP 2 LAST SIG_NAME PU_CPU1_UPI3_AC_COUPLING
J 0
(-1200 -1465);
DISPLAY 0.680851 (-1200 -1465);
PAINT WHITE (-1200 -1465);
WIRE 16 -1 (-1625 -1350)(-350 -1350);
FORCEPROP 2 LAST SIG_NAME PU_CPU1_UPI2_AC_COUPLING
J 0
(-1200 -1340);
DISPLAY 0.680851 (-1200 -1340);
PAINT WHITE (-1200 -1340);
WIRE 16 -1 (-1625 -1225)(-350 -1225);
FORCEPROP 2 LAST SIG_NAME PU_CPU1_UPI1_AC_COUPLING
J 0
(-1200 -1215);
DISPLAY 0.680851 (-1200 -1215);
PAINT WHITE (-1200 -1215);
WIRE 16 -1 (-1625 -1100)(-350 -1100);
FORCEPROP 2 LAST SIG_NAME PU_CPU1_UPI0_AC_COUPLING
J 0
(-1200 -1090);
DISPLAY 0.680851 (-1200 -1090);
PAINT WHITE (-1200 -1090);
WIRE 16 -1 (-2050 -150)(-1800 -150);
WIRE 16 -1 (-2050 -25)(-2050 -150);
WIRE 16 -1 (-2050 -25)(-1800 -25);
WIRE 16 -1 (-2050 100)(-2050 -25);
WIRE 16 -1 (-2050 100)(-1800 100);
WIRE 16 -1 (-2050 225)(-2050 100);
WIRE 16 -1 (-2050 225)(-1800 225);
WIRE 16 -1 (-1600 -25)(-325 -25);
FORCEPROP 2 LAST SIG_NAME PU_CPU0_UPI2_AC_COUPLING
J 0
(-1175 -15);
DISPLAY 0.680851 (-1175 -15);
PAINT WHITE (-1175 -15);
DOT 1 (-2075 -1100);
DOT 1 (-2075 -1225);
DOT 1 (-2075 -1350);
DOT 1 (-2050 -25);
DOT 1 (-2050 100);
DOT 1 (-2050 225);
FORCENOTE
CPU0 UPI
(-1550 500) 0;
DISPLAY LEFT (-1550 500);
DISPLAY 4.127660 (-1550 500);
PAINT WHITE (-1550 500);
FORCENOTE
CPU1 UPI
(-1575 -825) 0;
DISPLAY LEFT (-1575 -825);
DISPLAY 4.127660 (-1575 -825);
PAINT WHITE (-1575 -825);
QUIT
